# T6G (Grand Teton) — schematic netlist excerpt (pin names and nets, part order shuffled) for the footprints in the layout excerpt that follows; sources: Cadence DE-HDL packaged netlist, KiCad conversion of 04192023_DAF0TMB3IC0_F0TG_MB_C_brd_V02_OCP.brd

C938  Q_CAP_DIFFBUS  DIFF BUS_0.22UF 6.3V 20% X6S  pkg C0201  page 63 : \1\ = P5E_CPU0_P1_TX_C_DN<13> ; \2\ = P5E_CPU0_P1_TX_DN<13>
PC585_1  Q_CAP  1UF 25V 10% X6S  pkg C0402  page 198 : A = SW_P12V_AUX_PVDDCR_SOC_P0_FLT ; B = GND

(kicad_pcb
	(version 20260206)
	(generator "pcbnew")
	(generator_version "10.0")
	(general
		(thickness 1.6)
		(legacy_teardrops no)
	)
	(paper "A4")
	(title_block
		(title "04192023_DAF0TMB3IC0_F0TG_MB_C_brd_V02_OCP.brd")
		(comment 1 "Grand Teton / footprints 637-638 of 8354")
	)
	(layers
		(0 "F.Cu" signal "TOP")
		(4 "In1.Cu" signal "GND")
		(6 "In2.Cu" signal "IN1")
		(8 "In3.Cu" signal "GND1")
		(10 "In4.Cu" signal "IN2")
		(12 "In5.Cu" signal "GND2")
		(14 "In6.Cu" signal "IN3")
		(16 "In7.Cu" signal "GND3")
		(18 "In8.Cu" signal "VCC")
		(20 "In9.Cu" signal "VCC1")
		(22 "In10.Cu" signal "GND4")
		(24 "In11.Cu" signal "IN4")
		(26 "In12.Cu" signal "GND5")
		(28 "In13.Cu" signal "IN5")
		(30 "In14.Cu" signal "GND6")
		(32 "In15.Cu" signal "IN6")
		(34 "In16.Cu" signal "GND7")
		(2 "B.Cu" signal "BOTTOM")
		(9 "F.Adhes" user "F.Adhesive")
		(11 "B.Adhes" user "B.Adhesive")
		(13 "F.Paste" user "Package Geometry/Pastemask Top")
		(15 "B.Paste" user "Package Geometry/Pastemask Bottom")
		(5 "F.SilkS" user "Ref Des/Silkscreen Top")
		(7 "B.SilkS" user "Ref Des/Silkscreen Bottom")
		(1 "F.Mask" user "Board Geometry/Soldermask Top")
		(3 "B.Mask" user "Board Geometry/Soldermask Bottom")
		(17 "Dwgs.User" user "User.Drawings")
		(19 "Cmts.User" user "User.Comments")
		(21 "Eco1.User" user "User.Eco1")
		(23 "Eco2.User" user "User.Eco2")
		(25 "Edge.Cuts" user "Board Geometry/Outline")
		(27 "Margin" user)
		(31 "F.CrtYd" user "Package Geometry/Place Bound Top")
		(29 "B.CrtYd" user "Package Geometry/Place Bound Bottom")
		(35 "F.Fab" user "Ref Des/Assembly Top")
		(33 "B.Fab" user "Ref Des/Assembly Bottom")
	)
	(footprint ""
		(layer "F.Cu")
		(at 394.164058 -177.04562 90)
		(property "Reference" "PC585_1"
			(at 0 0 90)
			(layer "F.SilkS")
			(hide yes)
			(effects
				(font
					(size 1.27 1.27)
				)
			)
		)
		(property "Value" ""
			(at 0 0 90)
			(layer "F.Fab")
			(effects
				(font
					(size 1.27 1.27)
				)
			)
		)
		(duplicate_pad_numbers_are_jumpers no)
		(fp_line
			(start 0.7874 -0.4064)
			(end 0.7874 0.4064)
			(stroke
				(width 0.1524)
				(type default)
			)
			(layer "F.SilkS")
		)
		(fp_line
			(start -0.7874 -0.4064)
			(end 0.7874 -0.4064)
			(stroke
				(width 0.1524)
				(type default)
			)
			(layer "F.SilkS")
		)
		(fp_line
			(start 0.7874 0.4064)
			(end -0.7874 0.4064)
			(stroke
				(width 0.1524)
				(type default)
			)
			(layer "F.SilkS")
		)
		(fp_line
			(start -0.7874 0.4064)
			(end -0.7874 -0.4064)
			(stroke
				(width 0.1524)
				(type default)
			)
			(layer "F.SilkS")
		)
		(fp_line
			(start -0.12065 -0.305054)
			(end -0.12065 -0.2794)
			(stroke
				(width 0.1)
				(type default)
			)
			(layer "F.Fab")
		)
		(fp_line
			(start -0.67945 -0.305054)
			(end -0.12065 -0.305054)
			(stroke
				(width 0.1)
				(type default)
			)
			(layer "F.Fab")
		)
		(fp_line
			(start 0.67945 -0.3048)
			(end 0.67945 0.3048)
			(stroke
				(width 0.1)
				(type default)
			)
			(layer "F.Fab")
		)
		(fp_line
			(start 0.12065 -0.3048)
			(end 0.67945 -0.3048)
			(stroke
				(width 0.1)
				(type default)
			)
			(layer "F.Fab")
		)
		(fp_line
			(start 0.12065 -0.2794)
			(end 0.12065 -0.3048)
			(stroke
				(width 0.1)
				(type default)
			)
			(layer "F.Fab")
		)
		(fp_line
			(start -0.12065 -0.2794)
			(end 0.12065 -0.2794)
			(stroke
				(width 0.1)
				(type default)
			)
			(layer "F.Fab")
		)
		(fp_line
			(start 0.120396 0.2794)
			(end -0.12065 0.2794)
			(stroke
				(width 0.1)
				(type default)
			)
			(layer "F.Fab")
		)
		(fp_line
			(start -0.12065 0.2794)
			(end -0.12065 0.3048)
			(stroke
				(width 0.1)
				(type default)
			)
			(layer "F.Fab")
		)
		(fp_line
			(start 0.67945 0.3048)
			(end 0.120396 0.3048)
			(stroke
				(width 0.1)
				(type default)
			)
			(layer "F.Fab")
		)
		(fp_line
			(start 0.120396 0.3048)
			(end 0.120396 0.2794)
			(stroke
				(width 0.1)
				(type default)
			)
			(layer "F.Fab")
		)
		(fp_line
			(start -0.12065 0.3048)
			(end -0.67945 0.3048)
			(stroke
				(width 0.1)
				(type default)
			)
			(layer "F.Fab")
		)
		(fp_line
			(start -0.67945 0.3048)
			(end -0.67945 -0.305054)
			(stroke
				(width 0.1)
				(type default)
			)
			(layer "F.Fab")
		)
		(pad "1" smd circle
			(at -0.40005 0 90)
			(size 0 0)
			(layers "F.Cu" "F.Mask" "F.Paste")
			(net "SW_P12V_AUX_PVDDCR_SOC_P0_FLT")
		)
		(pad "2" smd circle
			(at 0.40005 0 90)
			(size 0 0)
			(layers "F.Cu" "F.Mask" "F.Paste")
			(net "GND")
		)
	)
	(footprint ""
		(layer "F.Cu")
		(at 357.958644 -378.95403 -90)
		(property "Reference" "C938"
			(at 0 0 270)
			(layer "F.SilkS")
			(hide yes)
			(effects
				(font
					(size 1.27 1.27)
				)
			)
		)
		(property "Value" ""
			(at 0 0 270)
			(layer "F.Fab")
			(effects
				(font
					(size 1.27 1.27)
				)
			)
		)
		(duplicate_pad_numbers_are_jumpers no)
		(fp_line
			(start -0.299974 0.150114)
			(end -0.299974 -0.150114)
			(stroke
				(width 0.1)
				(type default)
			)
			(layer "F.Fab")
		)
		(fp_line
			(start 0.299974 0.150114)
			(end -0.299974 0.150114)
			(stroke
				(width 0.1)
				(type default)
			)
			(layer "F.Fab")
		)
		(fp_line
			(start -0.299974 -0.150114)
			(end 0.299974 -0.150114)
			(stroke
				(width 0.1)
				(type default)
			)
			(layer "F.Fab")
		)
		(fp_line
			(start 0.299974 -0.150114)
			(end 0.299974 0.150114)
			(stroke
				(width 0.1)
				(type default)
			)
			(layer "F.Fab")
		)
		(pad "1" smd rect
			(at -0.2667 0 270)
			(size 0.3048 0.381)
			(layers "F.Cu" "F.Mask" "F.Paste")
			(net "P5E_CPU0_P1_TX_C_DN<13>")
		)
		(pad "2" smd rect
			(at 0.2667 0 270)
			(size 0.3048 0.381)
			(layers "F.Cu" "F.Mask" "F.Paste")
			(net "P5E_CPU0_P1_TX_DN<13>")
		)
	)
)
